# T6G (Grand Teton) — schematic netlist excerpt (pin names and nets, part order shuffled) for the footprints in the layout excerpt that follows; sources: Cadence DE-HDL packaged netlist, KiCad conversion of 04192023_DAF0TMB3IC0_F0TG_MB_C_brd_V02_OCP.brd

PC6016  Q_CAP  3300PF 50V 10% X7R  pkg 0402  page 270 : A = P1V2_AUX_REF ; B = GND
PL6511  Q_INDUCTOR  120NH/69A IND  pkg SMLF  page 365 : \1\ = SW_P0V9_RETIMER_CPU1_SW1 ; \2\ = P0V9_CPU1_RT_2D
PR1101  Q_RES  2K 0.1% CHIP  pkg 0402LF  page 263 : A = HSC_IMON ; B = AGND_HSC

(kicad_pcb
	(version 20260206)
	(generator "pcbnew")
	(generator_version "10.0")
	(general
		(thickness 1.6)
		(legacy_teardrops no)
	)
	(paper "A4")
	(title_block
		(title "04192023_DAF0TMB3IC0_F0TG_MB_C_brd_V02_OCP.brd")
		(comment 1 "Grand Teton / footprints 378-380 of 8354")
	)
	(layers
		(0 "F.Cu" signal "TOP")
		(4 "In1.Cu" signal "GND")
		(6 "In2.Cu" signal "IN1")
		(8 "In3.Cu" signal "GND1")
		(10 "In4.Cu" signal "IN2")
		(12 "In5.Cu" signal "GND2")
		(14 "In6.Cu" signal "IN3")
		(16 "In7.Cu" signal "GND3")
		(18 "In8.Cu" signal "VCC")
		(20 "In9.Cu" signal "VCC1")
		(22 "In10.Cu" signal "GND4")
		(24 "In11.Cu" signal "IN4")
		(26 "In12.Cu" signal "GND5")
		(28 "In13.Cu" signal "IN5")
		(30 "In14.Cu" signal "GND6")
		(32 "In15.Cu" signal "IN6")
		(34 "In16.Cu" signal "GND7")
		(2 "B.Cu" signal "BOTTOM")
		(9 "F.Adhes" user "F.Adhesive")
		(11 "B.Adhes" user "B.Adhesive")
		(13 "F.Paste" user "Package Geometry/Pastemask Top")
		(15 "B.Paste" user "Package Geometry/Pastemask Bottom")
		(5 "F.SilkS" user "Ref Des/Silkscreen Top")
		(7 "B.SilkS" user "Ref Des/Silkscreen Bottom")
		(1 "F.Mask" user "Board Geometry/Soldermask Top")
		(3 "B.Mask" user "Board Geometry/Soldermask Bottom")
		(17 "Dwgs.User" user "User.Drawings")
		(19 "Cmts.User" user "User.Comments")
		(21 "Eco1.User" user "User.Eco1")
		(23 "Eco2.User" user "User.Eco2")
		(25 "Edge.Cuts" user "Board Geometry/Outline")
		(27 "Margin" user)
		(31 "F.CrtYd" user "Package Geometry/Place Bound Top")
		(29 "B.CrtYd" user "Package Geometry/Place Bound Bottom")
		(35 "F.Fab" user "Ref Des/Assembly Top")
		(33 "B.Fab" user "Ref Des/Assembly Bottom")
	)
	(footprint ""
		(layer "F.Cu")
		(at 122.3772 -73.271126 180)
		(property "Reference" "PC6016"
			(at 0 0 180)
			(layer "F.SilkS")
			(hide yes)
			(effects
				(font
					(size 1.27 1.27)
				)
			)
		)
		(property "Value" ""
			(at 0 0 180)
			(layer "F.Fab")
			(effects
				(font
					(size 1.27 1.27)
				)
			)
		)
		(duplicate_pad_numbers_are_jumpers no)
		(fp_line
			(start 0.7874 0.4064)
			(end -0.7874 0.4064)
			(stroke
				(width 0.1524)
				(type default)
			)
			(layer "F.SilkS")
		)
		(fp_line
			(start 0.7874 -0.4064)
			(end 0.7874 0.4064)
			(stroke
				(width 0.1524)
				(type default)
			)
			(layer "F.SilkS")
		)
		(fp_line
			(start -0.7874 0.4064)
			(end -0.7874 -0.4064)
			(stroke
				(width 0.1524)
				(type default)
			)
			(layer "F.SilkS")
		)
		(fp_line
			(start -0.7874 -0.4064)
			(end 0.7874 -0.4064)
			(stroke
				(width 0.1524)
				(type default)
			)
			(layer "F.SilkS")
		)
		(fp_line
			(start 0.67945 0.3048)
			(end 0.120396 0.3048)
			(stroke
				(width 0.1)
				(type default)
			)
			(layer "F.Fab")
		)
		(fp_line
			(start 0.67945 -0.3048)
			(end 0.67945 0.3048)
			(stroke
				(width 0.1)
				(type default)
			)
			(layer "F.Fab")
		)
		(fp_line
			(start 0.12065 -0.2794)
			(end 0.12065 -0.3048)
			(stroke
				(width 0.1)
				(type default)
			)
			(layer "F.Fab")
		)
		(fp_line
			(start 0.12065 -0.3048)
			(end 0.67945 -0.3048)
			(stroke
				(width 0.1)
				(type default)
			)
			(layer "F.Fab")
		)
		(fp_line
			(start 0.120396 0.3048)
			(end 0.120396 0.2794)
			(stroke
				(width 0.1)
				(type default)
			)
			(layer "F.Fab")
		)
		(fp_line
			(start 0.120396 0.2794)
			(end -0.12065 0.2794)
			(stroke
				(width 0.1)
				(type default)
			)
			(layer "F.Fab")
		)
		(fp_line
			(start -0.12065 0.3048)
			(end -0.67945 0.3048)
			(stroke
				(width 0.1)
				(type default)
			)
			(layer "F.Fab")
		)
		(fp_line
			(start -0.12065 0.2794)
			(end -0.12065 0.3048)
			(stroke
				(width 0.1)
				(type default)
			)
			(layer "F.Fab")
		)
		(fp_line
			(start -0.12065 -0.2794)
			(end 0.12065 -0.2794)
			(stroke
				(width 0.1)
				(type default)
			)
			(layer "F.Fab")
		)
		(fp_line
			(start -0.12065 -0.305054)
			(end -0.12065 -0.2794)
			(stroke
				(width 0.1)
				(type default)
			)
			(layer "F.Fab")
		)
		(fp_line
			(start -0.67945 0.3048)
			(end -0.67945 -0.305054)
			(stroke
				(width 0.1)
				(type default)
			)
			(layer "F.Fab")
		)
		(fp_line
			(start -0.67945 -0.305054)
			(end -0.12065 -0.305054)
			(stroke
				(width 0.1)
				(type default)
			)
			(layer "F.Fab")
		)
		(pad "1" smd circle
			(at -0.40005 0 180)
			(size 0 0)
			(layers "F.Cu" "F.Mask" "F.Paste")
			(net "P1V2_AUX_REF")
		)
		(pad "2" smd circle
			(at 0.40005 0 180)
			(size 0 0)
			(layers "F.Cu" "F.Mask" "F.Paste")
			(net "GND")
		)
	)
	(footprint ""
		(layer "F.Cu")
		(at 18.064734 -381.6858 -90)
		(property "Reference" "PL6511"
			(at 3.3528 3.814064 90)
			(unlocked yes)
			(layer "F.SilkS")
			(effects
				(font
					(size 0.7874 0.5842)
					(thickness 0.1524)
				)
				(justify left)
			)
		)
		(property "Value" ""
			(at 0 0 270)
			(layer "F.Fab")
			(effects
				(font
					(size 1.27 1.27)
				)
			)
		)
		(duplicate_pad_numbers_are_jumpers no)
		(fp_line
			(start -3.24993 3.24993)
			(end -3.24993 2.2352)
			(stroke
				(width 0.1524)
				(type default)
			)
			(layer "F.SilkS")
		)
		(fp_line
			(start 3.24993 3.24993)
			(end -3.24993 3.24993)
			(stroke
				(width 0.1524)
				(type default)
			)
			(layer "F.SilkS")
		)
		(fp_line
			(start 3.24993 2.2352)
			(end 3.24993 3.24993)
			(stroke
				(width 0.1524)
				(type default)
			)
			(layer "F.SilkS")
		)
		(fp_line
			(start -3.24993 -2.2352)
			(end -3.24993 -3.24993)
			(stroke
				(width 0.1524)
				(type default)
			)
			(layer "F.SilkS")
		)
		(fp_line
			(start -3.24993 -3.24993)
			(end 3.24993 -3.24993)
			(stroke
				(width 0.1524)
				(type default)
			)
			(layer "F.SilkS")
		)
		(fp_line
			(start 3.24993 -3.24993)
			(end 3.24993 -2.2352)
			(stroke
				(width 0.1524)
				(type default)
			)
			(layer "F.SilkS")
		)
		(fp_line
			(start -3.24993 3.24993)
			(end -3.24993 -3.24993)
			(stroke
				(width 0.1)
				(type default)
			)
			(layer "F.Fab")
		)
		(fp_line
			(start 3.24993 3.24993)
			(end -3.24993 3.24993)
			(stroke
				(width 0.1)
				(type default)
			)
			(layer "F.Fab")
		)
		(fp_line
			(start -3.24993 -3.24993)
			(end 3.24993 -3.24993)
			(stroke
				(width 0.1)
				(type default)
			)
			(layer "F.Fab")
		)
		(fp_line
			(start 3.24993 -3.24993)
			(end 3.24993 3.24993)
			(stroke
				(width 0.1)
				(type default)
			)
			(layer "F.Fab")
		)
		(pad "1" smd rect
			(at -2.29997 0 270)
			(size 2.0066 4.2164)
			(layers "F.Cu" "F.Mask" "F.Paste")
			(net "SW_P0V9_RETIMER_CPU1_SW1")
		)
		(pad "2" smd rect
			(at 2.29997 0 270)
			(size 2.0066 4.2164)
			(layers "F.Cu" "F.Mask" "F.Paste")
			(net "P0V9_CPU1_RT_2D")
		)
	)
	(footprint ""
		(layer "F.Cu")
		(at 204.7621 -401.988782 180)
		(property "Reference" "PR1101"
			(at 0 0 180)
			(layer "F.SilkS")
			(hide yes)
			(effects
				(font
					(size 1.27 1.27)
				)
			)
		)
		(property "Value" ""
			(at 0 0 180)
			(layer "F.Fab")
			(effects
				(font
					(size 1.27 1.27)
				)
			)
		)
		(duplicate_pad_numbers_are_jumpers no)
		(fp_line
			(start 0.7874 0.4064)
			(end -0.7874 0.4064)
			(stroke
				(width 0.1524)
				(type default)
			)
			(layer "F.SilkS")
		)
		(fp_line
			(start 0.7874 -0.4064)
			(end 0.7874 0.4064)
			(stroke
				(width 0.1524)
				(type default)
			)
			(layer "F.SilkS")
		)
		(fp_line
			(start -0.7874 0.4064)
			(end -0.7874 -0.4064)
			(stroke
				(width 0.1524)
				(type default)
			)
			(layer "F.SilkS")
		)
		(fp_line
			(start -0.7874 -0.4064)
			(end 0.7874 -0.4064)
			(stroke
				(width 0.1524)
				(type default)
			)
			(layer "F.SilkS")
		)
		(fp_line
			(start 0.67945 0.3048)
			(end 0.120396 0.3048)
			(stroke
				(width 0.1)
				(type default)
			)
			(layer "F.Fab")
		)
		(fp_line
			(start 0.67945 -0.3048)
			(end 0.67945 0.3048)
			(stroke
				(width 0.1)
				(type default)
			)
			(layer "F.Fab")
		)
		(fp_line
			(start 0.12065 -0.2794)
			(end 0.12065 -0.3048)
			(stroke
				(width 0.1)
				(type default)
			)
			(layer "F.Fab")
		)
		(fp_line
			(start 0.12065 -0.3048)
			(end 0.67945 -0.3048)
			(stroke
				(width 0.1)
				(type default)
			)
			(layer "F.Fab")
		)
		(fp_line
			(start 0.120396 0.3048)
			(end 0.120396 0.2794)
			(stroke
				(width 0.1)
				(type default)
			)
			(layer "F.Fab")
		)
		(fp_line
			(start 0.120396 0.2794)
			(end -0.12065 0.2794)
			(stroke
				(width 0.1)
				(type default)
			)
			(layer "F.Fab")
		)
		(fp_line
			(start -0.12065 0.3048)
			(end -0.67945 0.3048)
			(stroke
				(width 0.1)
				(type default)
			)
			(layer "F.Fab")
		)
		(fp_line
			(start -0.12065 0.2794)
			(end -0.12065 0.3048)
			(stroke
				(width 0.1)
				(type default)
			)
			(layer "F.Fab")
		)
		(fp_line
			(start -0.12065 -0.2794)
			(end 0.12065 -0.2794)
			(stroke
				(width 0.1)
				(type default)
			)
			(layer "F.Fab")
		)
		(fp_line
			(start -0.12065 -0.305054)
			(end -0.12065 -0.2794)
			(stroke
				(width 0.1)
				(type default)
			)
			(layer "F.Fab")
		)
		(fp_line
			(start -0.67945 0.3048)
			(end -0.67945 -0.305054)
			(stroke
				(width 0.1)
				(type default)
			)
			(layer "F.Fab")
		)
		(fp_line
			(start -0.67945 -0.305054)
			(end -0.12065 -0.305054)
			(stroke
				(width 0.1)
				(type default)
			)
			(layer "F.Fab")
		)
		(pad "1" smd circle
			(at -0.40005 0 180)
			(size 0 0)
			(layers "F.Cu" "F.Mask" "F.Paste")
			(net "HSC_IMON")
		)
		(pad "2" smd circle
			(at 0.40005 0 180)
			(size 0 0)
			(layers "F.Cu" "F.Mask" "F.Paste")
			(net "AGND_HSC")
		)
	)
)
